# TIMECARD (Time Appliance Project (Time Card)) — schematic netlist excerpt (pin names and nets, part order shuffled) for the footprints in the layout excerpt that follows; sources: Cadence DE-HDL packaged netlist, KiCad conversion of R4006-B0001-02_R01.brd

R231  RESISTOR  4.22KOHM 1%  pkg SMC_0402R  page 31 : \1\ = XP2R5V_FPGA ; \2\ = UNNAMED_515_ISL80101IRAJZDFN10_
R426  RESISTOR  100OHM 1%  pkg SMC_0402R_H016  page 26 : \1\ = FPGA_OUT_GPS_LED_GREEN_N ; \2\ = UNNAMED_14_LED4PV14_I269_4

(kicad_pcb
	(version 20260206)
	(generator "pcbnew")
	(generator_version "10.0")
	(general
		(thickness 1.6)
		(legacy_teardrops no)
	)
	(paper "A4")
	(title_block
		(title "timecard-production-celestica-r4006 — R4006-B0001-02_R01.brd")
		(comment 1 "Time Appliance Project (Time Card) / footprints 425-426 of 1113")
	)
	(layers
		(0 "F.Cu" signal "TOP")
		(4 "In1.Cu" signal "L02_GND1")
		(6 "In2.Cu" signal "L03_SIG1")
		(8 "In3.Cu" signal "L04_GND2")
		(10 "In4.Cu" signal "L05_VCC1")
		(12 "In5.Cu" signal "L06_VCC2")
		(14 "In6.Cu" signal "L07_GND3")
		(16 "In7.Cu" signal "L08_SIG2")
		(18 "In8.Cu" signal "L09_GND4")
		(2 "B.Cu" signal "BOTTOM")
		(9 "F.Adhes" user "F.Adhesive")
		(11 "B.Adhes" user "B.Adhesive")
		(13 "F.Paste" user "Package Geometry/Pastemask Top")
		(15 "B.Paste" user "Package Geometry/Pastemask Bottom")
		(5 "F.SilkS" user "Ref Des/Silkscreen Top")
		(7 "B.SilkS" user "Ref Des/Silkscreen Bottom")
		(1 "F.Mask" user "Board Geometry/Soldermask Top")
		(3 "B.Mask" user "Board Geometry/Soldermask Bottom")
		(17 "Dwgs.User" user "User.Drawings")
		(19 "Cmts.User" user "User.Comments")
		(21 "Eco1.User" user "User.Eco1")
		(23 "Eco2.User" user "User.Eco2")
		(25 "Edge.Cuts" user "Board Geometry/Outline")
		(27 "Margin" user)
		(31 "F.CrtYd" user "Package Geometry/Place Bound Top")
		(29 "B.CrtYd" user "Package Geometry/Place Bound Bottom")
		(35 "F.Fab" user "Ref Des/Assembly Top")
		(33 "B.Fab" user "Ref Des/Assembly Bottom")
	)
	(footprint ""
		(layer "F.Cu")
		(at 9.652 -81.534 90)
		(property "Reference" "R426"
			(at -2.667 -0.08763 90)
			(unlocked yes)
			(layer "F.SilkS")
			(effects
				(font
					(size 0.7874 0.5842)
					(thickness 0.1524)
				)
			)
		)
		(property "Value" "VAL*"
			(at 0.02032 2.13233 90)
			(unlocked yes)
			(layer "F.Fab")
			(hide yes)
			(effects
				(font
					(size 0.7874 0.5842)
					(thickness 0.1524)
				)
			)
		)
		(property "Device Type" "RESISTOR-G155-11000-01,100OHM,A"
			(at 0.008382 1.210564 90)
			(unlocked yes)
			(layer "F.Fab")
			(hide yes)
			(effects
				(font
					(size 0.7874 0.5842)
					(thickness 0.1524)
				)
			)
		)
		(property "User Part Number" "PARTNUM*"
			(at 0.02032 4.024884 90)
			(unlocked yes)
			(layer "Cmts.User")
			(hide yes)
			(effects
				(font
					(size 0.7874 0.5842)
					(thickness 0.1524)
				)
			)
		)
		(property "Tolerance" "TOL*"
			(at 0.044704 3.05435 90)
			(unlocked yes)
			(layer "Cmts.User")
			(hide yes)
			(effects
				(font
					(size 0.7874 0.5842)
					(thickness 0.1524)
				)
			)
		)
		(duplicate_pad_numbers_are_jumpers no)
		(fp_line
			(start 1.143 -0.5588)
			(end -1.143 -0.5588)
			(stroke
				(width 0.1)
				(type default)
			)
			(layer "F.SilkS")
		)
		(fp_line
			(start -1.143 -0.5588)
			(end -1.143 0.5588)
			(stroke
				(width 0.1)
				(type default)
			)
			(layer "F.SilkS")
		)
		(fp_line
			(start 1.143 0.5588)
			(end 1.143 -0.5588)
			(stroke
				(width 0.1)
				(type default)
			)
			(layer "F.SilkS")
		)
		(fp_line
			(start -1.143 0.5588)
			(end 1.143 0.5588)
			(stroke
				(width 0.1)
				(type default)
			)
			(layer "F.SilkS")
		)
		(fp_poly
			(pts
				(xy -1.143 0.5588) (xy 1.143 0.5588) (xy 1.143 -0.5588) (xy -1.143 -0.5588)
			)
			(stroke
				(width 0)
				(type default)
			)
			(fill no)
			(layer "F.CrtYd")
		)
		(fp_line
			(start 0.508 -0.3048)
			(end -0.508 -0.3048)
			(stroke
				(width 0.1)
				(type default)
			)
			(layer "F.Fab")
		)
		(fp_line
			(start -0.508 -0.3048)
			(end -0.508 0.3048)
			(stroke
				(width 0.1)
				(type default)
			)
			(layer "F.Fab")
		)
		(fp_line
			(start 0.508 0.3048)
			(end 0.508 -0.3048)
			(stroke
				(width 0.1)
				(type default)
			)
			(layer "F.Fab")
		)
		(fp_line
			(start -0.508 0.3048)
			(end 0.508 0.3048)
			(stroke
				(width 0.1)
				(type default)
			)
			(layer "F.Fab")
		)
		(pad "1" smd rect
			(at -0.5334 0 90)
			(size 0.7112 0.6096)
			(layers "F.Cu" "F.Mask" "F.Paste")
			(net "FPGA_OUT_GPS_LED_GREEN_N")
		)
		(pad "2" smd rect
			(at 0.5334 0 90)
			(size 0.7112 0.6096)
			(layers "F.Cu" "F.Mask" "F.Paste")
			(net "UNNAMED_14_LED4PV14_I269_4")
		)
		(zone
			(layer "F.Cu")
			(hatch none 0.5)
			(connect_pads
				(clearance 0)
			)
			(min_thickness 0.25)
			(keepout
				(tracks allowed)
				(vias not_allowed)
				(pads allowed)
				(copperpour not_allowed)
				(footprints allowed)
			)
			(placement
				(enabled no)
				(sheetname "")
			)
			(fill
				(thermal_gap 0.5)
				(thermal_bridge_width 0.5)
				(island_removal_mode 0)
			)
			(polygon
				(pts
					(xy 9.9568 -81.4578) (xy 9.9568 -81.6102) (xy 9.3472 -81.6102) (xy 9.3472 -81.4578)
				)
			)
		)
		(zone
			(layer "F.Cu")
			(hatch none 0.5)
			(connect_pads
				(clearance 0)
			)
			(min_thickness 0.25)
			(keepout
				(tracks not_allowed)
				(vias allowed)
				(pads allowed)
				(copperpour not_allowed)
				(footprints allowed)
			)
			(placement
				(enabled no)
				(sheetname "")
			)
			(fill
				(thermal_gap 0.5)
				(thermal_bridge_width 0.5)
				(island_removal_mode 0)
			)
			(polygon
				(pts
					(xy 9.9568 -81.4578) (xy 9.9568 -81.6102) (xy 9.3472 -81.6102) (xy 9.3472 -81.4578)
				)
			)
		)
	)
	(footprint ""
		(layer "F.Cu")
		(at 137.795 -17.526)
		(property "Reference" "R231"
			(at -1.397 1.56337 0)
			(unlocked yes)
			(layer "F.SilkS")
			(effects
				(font
					(size 0.7874 0.5842)
					(thickness 0.1524)
				)
			)
		)
		(property "Value" "VAL*"
			(at 0.0508 2.245106 0)
			(unlocked yes)
			(layer "F.Fab")
			(hide yes)
			(effects
				(font
					(size 0.7874 0.5842)
					(thickness 0.1524)
				)
			)
		)
		(property "Tolerance" "TOL*"
			(at 0.0508 3.261106 0)
			(unlocked yes)
			(layer "Cmts.User")
			(hide yes)
			(effects
				(font
					(size 0.7874 0.5842)
					(thickness 0.1524)
				)
			)
		)
		(property "Device Type" "RESISTOR-G155-04221-01,4.22KOHA"
			(at 0.0762 1.254506 0)
			(unlocked yes)
			(layer "F.Fab")
			(hide yes)
			(effects
				(font
					(size 0.7874 0.5842)
					(thickness 0.1524)
				)
			)
		)
		(property "User Part Number" "PARTNUM*"
			(at 0.0762 4.302506 0)
			(unlocked yes)
			(layer "Cmts.User")
			(hide yes)
			(effects
				(font
					(size 0.7874 0.5842)
					(thickness 0.1524)
				)
			)
		)
		(duplicate_pad_numbers_are_jumpers no)
		(fp_line
			(start -1.143 -0.5588)
			(end -1.143 0.5588)
			(stroke
				(width 0.1)
				(type default)
			)
			(layer "F.SilkS")
		)
		(fp_line
			(start -1.143 0.5588)
			(end 1.143 0.5588)
			(stroke
				(width 0.1)
				(type default)
			)
			(layer "F.SilkS")
		)
		(fp_line
			(start 1.143 -0.5588)
			(end -1.143 -0.5588)
			(stroke
				(width 0.1)
				(type default)
			)
			(layer "F.SilkS")
		)
		(fp_line
			(start 1.143 0.5588)
			(end 1.143 -0.5588)
			(stroke
				(width 0.1)
				(type default)
			)
			(layer "F.SilkS")
		)
		(fp_rect
			(start -1.143 -0.5588)
			(end 1.143 0.5588)
			(stroke
				(width 0)
				(type default)
			)
			(fill no)
			(layer "F.CrtYd")
		)
		(fp_line
			(start -0.508 -0.3048)
			(end -0.508 0.3048)
			(stroke
				(width 0.1)
				(type default)
			)
			(layer "F.Fab")
		)
		(fp_line
			(start -0.508 0.3048)
			(end 0.508 0.3048)
			(stroke
				(width 0.1)
				(type default)
			)
			(layer "F.Fab")
		)
		(fp_line
			(start 0.508 -0.3048)
			(end -0.508 -0.3048)
			(stroke
				(width 0.1)
				(type default)
			)
			(layer "F.Fab")
		)
		(fp_line
			(start 0.508 0.3048)
			(end 0.508 -0.3048)
			(stroke
				(width 0.1)
				(type default)
			)
			(layer "F.Fab")
		)
		(pad "1" smd rect
			(at -0.5334 0)
			(size 0.7112 0.6096)
			(layers "F.Cu" "F.Mask" "F.Paste")
			(net "XP2R5V_FPGA")
		)
		(pad "2" smd rect
			(at 0.5334 0)
			(size 0.7112 0.6096)
			(layers "F.Cu" "F.Mask" "F.Paste")
			(net "UNNAMED_515_ISL80101IRAJZDFN10_")
		)
		(zone
			(layer "F.Cu")
			(hatch none 0.5)
			(connect_pads
				(clearance 0)
			)
			(min_thickness 0.25)
			(keepout
				(tracks allowed)
				(vias not_allowed)
				(pads allowed)
				(copperpour not_allowed)
				(footprints allowed)
			)
			(placement
				(enabled no)
				(sheetname "")
			)
			(fill
				(thermal_gap 0.5)
				(thermal_bridge_width 0.5)
				(island_removal_mode 0)
			)
			(polygon
				(pts
					(xy 137.7188 -17.8308) (xy 137.7188 -17.2212) (xy 137.8712 -17.2212) (xy 137.8712 -17.8308)
				)
			)
		)
	)
)
